(kicad_pcb
	(version 20260206)
	(generator "pcbnew")
	(generator_version "10.0")
	(general
		(thickness 1.6)
		(legacy_teardrops no)
	)
	(paper "A4")
	(title_block
		(title "12092022_DA0F0TFB6D0_F0T_FAN_BOARD_MP5048_D_brd_v02_OCP.brd")
		(comment 1 "Grand Teton / footprints 777-779 of 924")
	)
	(layers
		(0 "F.Cu" signal "TOP")
		(4 "In1.Cu" signal "GND")
		(6 "In2.Cu" signal "IN1")
		(8 "In3.Cu" signal "IN2")
		(10 "In4.Cu" signal "GND1")
		(2 "B.Cu" signal "BOTTOM")
		(9 "F.Adhes" user "F.Adhesive")
		(11 "B.Adhes" user "B.Adhesive")
		(13 "F.Paste" user "Package Geometry/Pastemask Top")
		(15 "B.Paste" user "Package Geometry/Pastemask Bottom")
		(5 "F.SilkS" user "Ref Des/Silkscreen Top")
		(7 "B.SilkS" user "Ref Des/Silkscreen Bottom")
		(1 "F.Mask" user "Board Geometry/Soldermask Top")
		(3 "B.Mask" user "Board Geometry/Soldermask Bottom")
		(17 "Dwgs.User" user "User.Drawings")
		(19 "Cmts.User" user "User.Comments")
		(21 "Eco1.User" user "User.Eco1")
		(23 "Eco2.User" user "User.Eco2")
		(25 "Edge.Cuts" user "Board Geometry/Outline")
		(27 "Margin" user)
		(31 "F.CrtYd" user "Package Geometry/Place Bound Top")
		(29 "B.CrtYd" user "Package Geometry/Place Bound Bottom")
		(35 "F.Fab" user "Ref Des/Assembly Top")
		(33 "B.Fab" user "Ref Des/Assembly Bottom")
	)
	(footprint ""
		(layer "B.Cu")
		(at 42.01668 -79.804768 180)
		(property "Reference" "PU5"
			(at -5.60832 -2.361438 0)
			(unlocked yes)
			(layer "B.SilkS")
			(effects
				(font
					(size 0.7874 0.5842)
					(thickness 0.1524)
				)
				(justify left mirror)
			)
		)
		(property "Value" ""
			(at 0 0 0)
			(layer "B.Fab")
			(effects
				(font
					(size 1.27 1.27)
				)
				(justify mirror)
			)
		)
		(duplicate_pad_numbers_are_jumpers no)
		(fp_line
			(start 2.549906 2.549906)
			(end 2.4384 2.549906)
			(stroke
				(width 0.1524)
				(type default)
			)
			(layer "B.SilkS")
		)
		(fp_line
			(start 2.549906 2.2352)
			(end 2.549906 2.549906)
			(stroke
				(width 0.1524)
				(type default)
			)
			(layer "B.SilkS")
		)
		(fp_line
			(start 2.549906 1.4986)
			(end 2.549906 1.7526)
			(stroke
				(width 0.1524)
				(type default)
			)
			(layer "B.SilkS")
		)
		(fp_line
			(start 2.549906 0.6858)
			(end 2.549906 0.9144)
			(stroke
				(width 0.1524)
				(type default)
			)
			(layer "B.SilkS")
		)
		(fp_line
			(start 2.549906 -0.9144)
			(end 2.549906 0.1016)
			(stroke
				(width 0.1524)
				(type default)
			)
			(layer "B.SilkS")
		)
		(fp_line
			(start 2.549906 -1.7526)
			(end 2.549906 -1.4986)
			(stroke
				(width 0.1524)
				(type default)
			)
			(layer "B.SilkS")
		)
		(fp_line
			(start 2.549906 -2.549906)
			(end 2.549906 -2.2352)
			(stroke
				(width 0.1524)
				(type default)
			)
			(layer "B.SilkS")
		)
		(fp_line
			(start 2.4384 -2.549906)
			(end 2.549906 -2.549906)
			(stroke
				(width 0.1524)
				(type default)
			)
			(layer "B.SilkS")
		)
		(fp_line
			(start 2.199894 -3.9624)
			(end 2.199894 -2.9464)
			(stroke
				(width 0.1524)
				(type default)
			)
			(layer "B.SilkS")
		)
		(fp_line
			(start 1.800098 2.9464)
			(end 1.800098 3.4544)
			(stroke
				(width 0.1524)
				(type default)
			)
			(layer "B.SilkS")
		)
		(fp_line
			(start 0.199898 -3.4544)
			(end 0.199898 -2.9464)
			(stroke
				(width 0.1524)
				(type default)
			)
			(layer "B.SilkS")
		)
		(fp_line
			(start -0.199898 2.9464)
			(end -0.199898 3.9624)
			(stroke
				(width 0.1524)
				(type default)
			)
			(layer "B.SilkS")
		)
		(fp_line
			(start -1.800098 -3.9624)
			(end -1.800098 -2.9464)
			(stroke
				(width 0.1524)
				(type default)
			)
			(layer "B.SilkS")
		)
		(fp_line
			(start -2.199894 2.9464)
			(end -2.199894 3.4544)
			(stroke
				(width 0.1524)
				(type default)
			)
			(layer "B.SilkS")
		)
		(fp_line
			(start -2.4384 2.549906)
			(end -2.549906 2.549906)
			(stroke
				(width 0.1524)
				(type default)
			)
			(layer "B.SilkS")
		)
		(fp_line
			(start -2.549906 2.549906)
			(end -2.549906 2.2352)
			(stroke
				(width 0.1524)
				(type default)
			)
			(layer "B.SilkS")
		)
		(fp_line
			(start -2.549906 1.7526)
			(end -2.549906 1.4986)
			(stroke
				(width 0.1524)
				(type default)
			)
			(layer "B.SilkS")
		)
		(fp_line
			(start -2.549906 0.9144)
			(end -2.549906 -0.1016)
			(stroke
				(width 0.1524)
				(type default)
			)
			(layer "B.SilkS")
		)
		(fp_line
			(start -2.549906 -0.6858)
			(end -2.549906 -0.9144)
			(stroke
				(width 0.1524)
				(type default)
			)
			(layer "B.SilkS")
		)
		(fp_line
			(start -2.549906 -1.4986)
			(end -2.549906 -1.7526)
			(stroke
				(width 0.1524)
				(type default)
			)
			(layer "B.SilkS")
		)
		(fp_line
			(start -2.549906 -2.2352)
			(end -2.549906 -2.549906)
			(stroke
				(width 0.1524)
				(type default)
			)
			(layer "B.SilkS")
		)
		(fp_line
			(start -2.549906 -2.549906)
			(end -2.4384 -2.549906)
			(stroke
				(width 0.1524)
				(type default)
			)
			(layer "B.SilkS")
		)
		(fp_poly
			(pts
				(xy 3.531362 -1.49606) (xy 2.939034 -1.199896) (xy 3.531362 -0.903732)
			)
			(stroke
				(width 0)
				(type default)
			)
			(fill yes)
			(layer "B.SilkS")
		)
		(fp_line
			(start 2.549906 2.549906)
			(end -2.549906 2.549906)
			(stroke
				(width 0.1)
				(type default)
			)
			(layer "B.Fab")
		)
		(fp_line
			(start 2.549906 -2.549906)
			(end 2.549906 2.549906)
			(stroke
				(width 0.1)
				(type default)
			)
			(layer "B.Fab")
		)
		(fp_line
			(start 2.199894 -3.9624)
			(end 2.199894 -2.9464)
			(stroke
				(width 0.1)
				(type default)
			)
			(layer "B.Fab")
		)
		(fp_line
			(start 1.800098 2.9464)
			(end 1.800098 3.4544)
			(stroke
				(width 0.1)
				(type default)
			)
			(layer "B.Fab")
		)
		(fp_line
			(start 0.199898 -3.4544)
			(end 0.199898 -2.9464)
			(stroke
				(width 0.1)
				(type default)
			)
			(layer "B.Fab")
		)
		(fp_line
			(start -0.199898 2.9464)
			(end -0.199898 3.9624)
			(stroke
				(width 0.1)
				(type default)
			)
			(layer "B.Fab")
		)
		(fp_line
			(start -1.800098 -3.9624)
			(end -1.800098 -2.9464)
			(stroke
				(width 0.1)
				(type default)
			)
			(layer "B.Fab")
		)
		(fp_line
			(start -2.199894 2.9464)
			(end -2.199894 3.4544)
			(stroke
				(width 0.1)
				(type default)
			)
			(layer "B.Fab")
		)
		(fp_line
			(start -2.549906 2.549906)
			(end -2.549906 -2.549906)
			(stroke
				(width 0.1)
				(type default)
			)
			(layer "B.Fab")
		)
		(fp_line
			(start -2.549906 -2.549906)
			(end 2.549906 -2.549906)
			(stroke
				(width 0.1)
				(type default)
			)
			(layer "B.Fab")
		)
		(fp_poly
			(pts
				(xy 3.7084 -1.584706) (xy 2.939034 -1.199896) (xy 3.7084 -0.81534)
			)
			(stroke
				(width 0)
				(type default)
			)
			(fill yes)
			(layer "B.Fab")
		)
		(fp_text user "3"
			(at 3.299968 1.1938 90)
			(unlocked yes)
			(layer "B.SilkS")
			(effects
				(font
					(size 0.635 0.4064)
					(thickness 0.1524)
				)
				(justify mirror)
			)
		)
		(fp_text user "30"
			(at 2.9464 -3.045968 180)
			(unlocked yes)
			(layer "B.SilkS")
			(effects
				(font
					(size 0.635 0.4064)
					(thickness 0.1524)
				)
				(justify mirror)
			)
		)
		(fp_text user "4"
			(at 2.6416 3.151632 180)
			(unlocked yes)
			(layer "B.SilkS")
			(effects
				(font
					(size 0.635 0.4064)
					(thickness 0.1524)
				)
				(justify mirror)
			)
		)
		(fp_text user "19"
			(at -2.8448 -3.096768 180)
			(unlocked yes)
			(layer "B.SilkS")
			(effects
				(font
					(size 0.635 0.4064)
					(thickness 0.1524)
				)
				(justify mirror)
			)
		)
		(fp_text user "15"
			(at -2.8956 3.126232 180)
			(unlocked yes)
			(layer "B.SilkS")
			(effects
				(font
					(size 0.635 0.4064)
					(thickness 0.1524)
				)
				(justify mirror)
			)
		)
		(fp_text user "18"
			(at -3.304032 -1.2192 90)
			(unlocked yes)
			(layer "B.SilkS")
			(effects
				(font
					(size 0.635 0.4064)
					(thickness 0.1524)
				)
				(justify mirror)
			)
		)
		(fp_text user "16"
			(at -3.329432 1.2192 90)
			(unlocked yes)
			(layer "B.SilkS")
			(effects
				(font
					(size 0.635 0.4064)
					(thickness 0.1524)
				)
				(justify mirror)
			)
		)
		(fp_text user "3"
			(at 3.299968 1.1938 90)
			(unlocked yes)
			(layer "B.Fab")
			(effects
				(font
					(size 0.635 0.4064)
					(thickness 0.1524)
				)
				(justify mirror)
			)
		)
		(fp_text user "30"
			(at 2.9464 -3.045968 180)
			(unlocked yes)
			(layer "B.Fab")
			(effects
				(font
					(size 0.635 0.4064)
					(thickness 0.1524)
				)
				(justify mirror)
			)
		)
		(fp_text user "4"
			(at 2.6416 3.151632 180)
			(unlocked yes)
			(layer "B.Fab")
			(effects
				(font
					(size 0.635 0.4064)
					(thickness 0.1524)
				)
				(justify mirror)
			)
		)
		(fp_text user "19"
			(at -2.8448 -3.096768 180)
			(unlocked yes)
			(layer "B.Fab")
			(effects
				(font
					(size 0.635 0.4064)
					(thickness 0.1524)
				)
				(justify mirror)
			)
		)
		(fp_text user "15"
			(at -2.8956 3.126232 180)
			(unlocked yes)
			(layer "B.Fab")
			(effects
				(font
					(size 0.635 0.4064)
					(thickness 0.1524)
				)
				(justify mirror)
			)
		)
		(fp_text user "18"
			(at -3.304032 -1.2192 90)
			(unlocked yes)
			(layer "B.Fab")
			(effects
				(font
					(size 0.635 0.4064)
					(thickness 0.1524)
				)
				(justify mirror)
			)
		)
		(fp_text user "16"
			(at -3.329432 1.2192 90)
			(unlocked yes)
			(layer "B.Fab")
			(effects
				(font
					(size 0.635 0.4064)
					(thickness 0.1524)
				)
				(justify mirror)
			)
		)
		(pad "1" smd circle
			(at 1.599946 -1.199896 90)
			(size 0 0)
			(layers "B.Cu" "B.Mask" "B.Paste")
			(net "P52V_HSC")
		)
		(pad "2" smd rect
			(at 1.549908 0.40005 270)
			(size 0.3048 2.5146)
			(layers "B.Cu" "B.Mask" "B.Paste")
			(net "P52V_HSC")
		)
		(pad "3" smd rect
			(at 1.549908 1.199896 270)
			(size 0.3048 2.5146)
			(layers "B.Cu" "B.Mask" "B.Paste")
			(net "P52V_FAN_2")
		)
		(pad "4" smd circle
			(at 2.199894 2.350008 180)
			(size 0 0)
			(layers "B.Cu" "B.Mask" "B.Paste")
			(net "P52V_FAN_2")
		)
		(pad "5" smd rect
			(at 1.800098 2.350008)
			(size 0.1778 0.9144)
			(layers "B.Cu" "B.Mask" "B.Paste")
			(net "P52V_FAN_2")
		)
		(pad "6" smd rect
			(at 1.400048 2.350008)
			(size 0.1778 0.9144)
			(layers "B.Cu" "B.Mask" "B.Paste")
			(net "P52V_FAN_2")
		)
		(pad "7" smd rect
			(at 0.999998 2.350008)
			(size 0.1778 0.9144)
			(layers "B.Cu" "B.Mask" "B.Paste")
			(net "P52V_FAN_2")
		)
		(pad "8" smd rect
			(at 0.599948 2.350008)
			(size 0.1778 0.9144)
			(layers "B.Cu" "B.Mask" "B.Paste")
			(net "P52V_FAN_2")
		)
		(pad "9" smd rect
			(at 0.199898 2.350008)
			(size 0.1778 0.9144)
			(layers "B.Cu" "B.Mask" "B.Paste")
			(net "P52V_FAN_2")
		)
		(pad "10" smd rect
			(at -0.199898 2.350008)
			(size 0.1778 0.9144)
			(layers "B.Cu" "B.Mask" "B.Paste")
			(net "P52V_FAN_2")
		)
		(pad "11" smd rect
			(at -0.599948 2.350008)
			(size 0.1778 0.9144)
			(layers "B.Cu" "B.Mask" "B.Paste")
			(net "P52V_FAN_2")
		)
		(pad "12" smd rect
			(at -0.999998 2.350008)
			(size 0.1778 0.9144)
			(layers "B.Cu" "B.Mask" "B.Paste")
			(net "P52V_FAN_2")
		)
		(pad "13" smd rect
			(at -1.400048 2.350008)
			(size 0.1778 0.9144)
			(layers "B.Cu" "B.Mask" "B.Paste")
			(net "P52V_FAN_2")
		)
		(pad "14" smd rect
			(at -1.800098 2.350008)
			(size 0.1778 0.9144)
			(layers "B.Cu" "B.Mask" "B.Paste")
			(net "P52V_FAN_2")
		)
		(pad "15" smd circle
			(at -2.199894 2.350008 180)
			(size 0 0)
			(layers "B.Cu" "B.Mask" "B.Paste")
			(net "P52V_FAN_2")
		)
		(pad "16" smd rect
			(at -1.549908 1.199896 270)
			(size 0.3048 2.5146)
			(layers "B.Cu" "B.Mask" "B.Paste")
			(net "P52V_FAN_2")
		)
		(pad "17" smd rect
			(at -1.549908 -0.40005 270)
			(size 0.3048 2.5146)
			(layers "B.Cu" "B.Mask" "B.Paste")
			(net "P52V_FAN_2")
		)
		(pad "18" smd rect
			(at -1.549908 -1.199896 270)
			(size 0.3048 2.5146)
			(layers "B.Cu" "B.Mask" "B.Paste")
			(net "P52V_HSC")
		)
		(pad "19" smd circle
			(at -2.199894 -2.350008)
			(size 0 0)
			(layers "B.Cu" "B.Mask" "B.Paste")
			(net "FAN_2_CS")
		)
		(pad "20" smd rect
			(at -1.800098 -2.350008)
			(size 0.1778 0.9144)
			(layers "B.Cu" "B.Mask" "B.Paste")
			(net "FAN_2_IMON")
		)
		(pad "21" smd rect
			(at -1.400048 -2.350008)
			(size 0.1778 0.9144)
			(layers "B.Cu" "B.Mask" "B.Paste")
			(net "FAN_2_SS")
		)
		(pad "22" smd rect
			(at -0.999998 -2.350008)
			(size 0.1778 0.9144)
			(layers "B.Cu" "B.Mask" "B.Paste")
			(net "FAN_2_FAULT")
		)
		(pad "23" smd rect
			(at -0.599948 -2.350008)
			(size 0.1778 0.9144)
			(layers "B.Cu" "B.Mask" "B.Paste")
			(net "FAN_2_TIMER")
		)
		(pad "24" smd rect
			(at -0.199898 -2.350008)
			(size 0.1778 0.9144)
			(layers "B.Cu" "B.Mask" "B.Paste")
			(net "FAN_2_CLREF")
		)
		(pad "25" smd rect
			(at 0.199898 -2.350008)
			(size 0.1778 0.9144)
			(layers "B.Cu" "B.Mask" "B.Paste")
			(net "GND")
		)
		(pad "26" smd rect
			(at 0.599948 -2.350008)
			(size 0.1778 0.9144)
			(layers "B.Cu" "B.Mask" "B.Paste")
			(net "FAN_2_ON")
		)
		(pad "27" smd rect
			(at 0.999998 -2.350008)
			(size 0.1778 0.9144)
			(layers "B.Cu" "B.Mask" "B.Paste")
			(net "FAN_2_P3V_R")
		)
		(pad "28" smd rect
			(at 1.400048 -2.350008)
			(size 0.1778 0.9144)
			(layers "B.Cu" "B.Mask" "B.Paste")
			(net "FAN_2_P5V")
		)
		(pad "29" smd rect
			(at 1.800098 -2.350008)
			(size 0.1778 0.9144)
			(layers "B.Cu" "B.Mask" "B.Paste")
			(net "FAN_2_TEMP")
		)
		(pad "30" smd circle
			(at 2.199894 -2.350008)
			(size 0 0)
			(layers "B.Cu" "B.Mask" "B.Paste")
			(net "FAN_2_MODE")
		)
	)
	(footprint ""
		(layer "B.Cu")
		(at 18.430494 -73.971912 -90)
		(property "Reference" "PR62"
			(at 0 0 90)
			(layer "B.SilkS")
			(hide yes)
			(effects
				(font
					(size 1.27 1.27)
				)
				(justify mirror)
			)
		)
		(property "Value" ""
			(at 0 0 90)
			(layer "B.Fab")
			(effects
				(font
					(size 1.27 1.27)
				)
				(justify mirror)
			)
		)
		(duplicate_pad_numbers_are_jumpers no)
		(fp_line
			(start -0.7874 0.4064)
			(end 0.7874 0.4064)
			(stroke
				(width 0.1524)
				(type default)
			)
			(layer "B.SilkS")
		)
		(fp_line
			(start 0.7874 0.4064)
			(end 0.7874 -0.4064)
			(stroke
				(width 0.1524)
				(type default)
			)
			(layer "B.SilkS")
		)
		(fp_line
			(start -0.7874 -0.4064)
			(end -0.7874 0.4064)
			(stroke
				(width 0.1524)
				(type default)
			)
			(layer "B.SilkS")
		)
		(fp_line
			(start 0.7874 -0.4064)
			(end -0.7874 -0.4064)
			(stroke
				(width 0.1524)
				(type default)
			)
			(layer "B.SilkS")
		)
		(fp_line
			(start -0.67945 0.3048)
			(end -0.120396 0.3048)
			(stroke
				(width 0.1)
				(type default)
			)
			(layer "B.Fab")
		)
		(fp_line
			(start -0.120396 0.3048)
			(end -0.120396 0.2794)
			(stroke
				(width 0.1)
				(type default)
			)
			(layer "B.Fab")
		)
		(fp_line
			(start 0.12065 0.3048)
			(end 0.67945 0.3048)
			(stroke
				(width 0.1)
				(type default)
			)
			(layer "B.Fab")
		)
		(fp_line
			(start 0.67945 0.3048)
			(end 0.67945 -0.305054)
			(stroke
				(width 0.1)
				(type default)
			)
			(layer "B.Fab")
		)
		(fp_line
			(start -0.120396 0.2794)
			(end 0.12065 0.2794)
			(stroke
				(width 0.1)
				(type default)
			)
			(layer "B.Fab")
		)
		(fp_line
			(start 0.12065 0.2794)
			(end 0.12065 0.3048)
			(stroke
				(width 0.1)
				(type default)
			)
			(layer "B.Fab")
		)
		(fp_line
			(start -0.12065 -0.2794)
			(end -0.12065 -0.3048)
			(stroke
				(width 0.1)
				(type default)
			)
			(layer "B.Fab")
		)
		(fp_line
			(start 0.12065 -0.2794)
			(end -0.12065 -0.2794)
			(stroke
				(width 0.1)
				(type default)
			)
			(layer "B.Fab")
		)
		(fp_line
			(start -0.67945 -0.3048)
			(end -0.67945 0.3048)
			(stroke
				(width 0.1)
				(type default)
			)
			(layer "B.Fab")
		)
		(fp_line
			(start -0.12065 -0.3048)
			(end -0.67945 -0.3048)
			(stroke
				(width 0.1)
				(type default)
			)
			(layer "B.Fab")
		)
		(fp_line
			(start 0.12065 -0.305054)
			(end 0.12065 -0.2794)
			(stroke
				(width 0.1)
				(type default)
			)
			(layer "B.Fab")
		)
		(fp_line
			(start 0.67945 -0.305054)
			(end 0.12065 -0.305054)
			(stroke
				(width 0.1)
				(type default)
			)
			(layer "B.Fab")
		)
		(pad "1" smd rect
			(at 0.40005 0 270)
			(size 0.4572 0.508)
			(layers "B.Cu" "B.Mask" "B.Paste")
			(net "GND")
		)
		(pad "2" smd rect
			(at -0.40005 0 270)
			(size 0.4572 0.508)
			(layers "B.Cu" "B.Mask" "B.Paste")
			(net "FAN_5_IMON")
		)
	)
	(footprint ""
		(layer "B.Cu")
		(at 16.906494 -71.177912 -90)
		(property "Reference" "U393"
			(at 1.200912 -3.005836 270)
			(unlocked yes)
			(layer "B.SilkS")
			(effects
				(font
					(size 0.7874 0.5842)
					(thickness 0.1524)
				)
				(justify left mirror)
			)
		)
		(property "Value" ""
			(at 0 0 90)
			(layer "B.Fab")
			(effects
				(font
					(size 1.27 1.27)
				)
				(justify mirror)
			)
		)
		(duplicate_pad_numbers_are_jumpers no)
		(fp_line
			(start -1.3462 1.1938)
			(end -1.3462 -1.1938)
			(stroke
				(width 0.1524)
				(type default)
			)
			(layer "B.SilkS")
		)
		(fp_line
			(start 1.3462 1.1938)
			(end -1.3462 1.1938)
			(stroke
				(width 0.1524)
				(type default)
			)
			(layer "B.SilkS")
		)
		(fp_line
			(start -1.3462 -1.1938)
			(end 1.3462 -1.1938)
			(stroke
				(width 0.1524)
				(type default)
			)
			(layer "B.SilkS")
		)
		(fp_line
			(start 1.3462 -1.1938)
			(end 1.3462 1.1684)
			(stroke
				(width 0.1524)
				(type default)
			)
			(layer "B.SilkS")
		)
		(fp_poly
			(pts
				(xy 1.447038 -0.760476) (xy 2.052066 -0.457962) (xy 2.052066 -1.06299)
			)
			(stroke
				(width 0)
				(type default)
			)
			(fill yes)
			(layer "B.SilkS")
		)
		(fp_line
			(start -0.674878 1.124966)
			(end -0.674878 -1.124966)
			(stroke
				(width 0.1)
				(type default)
			)
			(layer "B.Fab")
		)
		(fp_line
			(start 0.674878 1.124966)
			(end -0.674878 1.124966)
			(stroke
				(width 0.1)
				(type default)
			)
			(layer "B.Fab")
		)
		(fp_line
			(start -0.674878 -1.124966)
			(end 0.674878 -1.124966)
			(stroke
				(width 0.1)
				(type default)
			)
			(layer "B.Fab")
		)
		(fp_line
			(start 0.674878 -1.124966)
			(end 0.674878 1.124966)
			(stroke
				(width 0.1)
				(type default)
			)
			(layer "B.Fab")
		)
		(fp_poly
			(pts
				(xy 1.447038 -0.760476) (xy 2.052066 -0.457962) (xy 2.052066 -1.06299)
			)
			(stroke
				(width 0)
				(type default)
			)
			(fill yes)
			(layer "B.Fab")
		)
		(pad "1" smd rect
			(at 0.899922 -0.750062 90)
			(size 0.6096 0.6096)
			(layers "B.Cu" "B.Mask" "B.Paste")
			(net "NC_U393_P1")
		)
		(pad "2" smd rect
			(at 0.899922 0)
			(size 0.4064 0.6096)
			(layers "B.Cu" "B.Mask" "B.Paste")
			(net "FAN_5_PRSNT_BUF_N")
		)
		(pad "3" smd rect
			(at 0.899922 0.750062 90)
			(size 0.6096 0.6096)
			(layers "B.Cu" "B.Mask" "B.Paste")
			(net "GND")
		)
		(pad "4" smd rect
			(at -0.899922 0.750062 90)
			(size 0.6096 0.6096)
			(layers "B.Cu" "B.Mask" "B.Paste")
			(net "FAN_5_PRESENT")
		)
		(pad "5" smd rect
			(at -0.899922 -0.750062 90)
			(size 0.6096 0.6096)
			(layers "B.Cu" "B.Mask" "B.Paste")
			(net "P3V3_AUX")
		)
	)
)
